(kicad_pcb
	(version 20260206)
	(generator "pcbnew")
	(generator_version "10.0")
	(general
		(thickness 1.6)
		(legacy_teardrops no)
	)
	(paper "A4")
	(title_block
		(title "01162023_DA0F0TEBIF0_F0T_Expander_BD_F_brd_V02_OCP.brd")
		(comment 1 "Grand Teton / footprints 1335-1341 of 9728")
	)
	(layers
		(0 "F.Cu" signal "TOP")
		(4 "In1.Cu" signal "GND")
		(6 "In2.Cu" signal "VCC")
		(8 "In3.Cu" signal "VCC1")
		(10 "In4.Cu" signal "GND1")
		(12 "In5.Cu" signal "IN1")
		(14 "In6.Cu" signal "GND2")
		(16 "In7.Cu" signal "IN2")
		(18 "In8.Cu" signal "GND3")
		(20 "In9.Cu" signal "IN3")
		(22 "In10.Cu" signal "GND4")
		(24 "In11.Cu" signal "IN4")
		(26 "In12.Cu" signal "GND5")
		(28 "In13.Cu" signal "IN5")
		(30 "In14.Cu" signal "GND6")
		(32 "In15.Cu" signal "IN6")
		(34 "In16.Cu" signal "GND7")
		(2 "B.Cu" signal "BOTTOM")
		(9 "F.Adhes" user "F.Adhesive")
		(11 "B.Adhes" user "B.Adhesive")
		(13 "F.Paste" user "Package Geometry/Pastemask Top")
		(15 "B.Paste" user "Package Geometry/Pastemask Bottom")
		(5 "F.SilkS" user "Ref Des/Silkscreen Top")
		(7 "B.SilkS" user "Ref Des/Silkscreen Bottom")
		(1 "F.Mask" user "Board Geometry/Soldermask Top")
		(3 "B.Mask" user "Board Geometry/Soldermask Bottom")
		(17 "Dwgs.User" user "User.Drawings")
		(19 "Cmts.User" user "User.Comments")
		(21 "Eco1.User" user "User.Eco1")
		(23 "Eco2.User" user "User.Eco2")
		(25 "Edge.Cuts" user "Board Geometry/Outline")
		(27 "Margin" user)
		(31 "F.CrtYd" user "Package Geometry/Place Bound Top")
		(29 "B.CrtYd" user "Package Geometry/Place Bound Bottom")
		(35 "F.Fab" user "Ref Des/Assembly Top")
		(33 "B.Fab" user "Ref Des/Assembly Bottom")
	)
	(footprint ""
		(layer "F.Cu")
		(at 240.139474 -257.975862 -90)
		(property "Reference" "R6524"
			(at 0 0 270)
			(layer "F.SilkS")
			(hide yes)
			(effects
				(font
					(size 1.27 1.27)
				)
			)
		)
		(property "Value" ""
			(at 0 0 270)
			(layer "F.Fab")
			(effects
				(font
					(size 1.27 1.27)
				)
			)
		)
		(duplicate_pad_numbers_are_jumpers no)
		(fp_line
			(start -0.7874 0.4064)
			(end -0.7874 -0.4064)
			(stroke
				(width 0.1524)
				(type default)
			)
			(layer "F.SilkS")
		)
		(fp_line
			(start 0.7874 0.4064)
			(end -0.7874 0.4064)
			(stroke
				(width 0.1524)
				(type default)
			)
			(layer "F.SilkS")
		)
		(fp_line
			(start -0.7874 -0.4064)
			(end 0.7874 -0.4064)
			(stroke
				(width 0.1524)
				(type default)
			)
			(layer "F.SilkS")
		)
		(fp_line
			(start 0.7874 -0.4064)
			(end 0.7874 0.4064)
			(stroke
				(width 0.1524)
				(type default)
			)
			(layer "F.SilkS")
		)
		(fp_line
			(start -0.67945 0.3048)
			(end -0.67945 -0.305054)
			(stroke
				(width 0.1)
				(type default)
			)
			(layer "F.Fab")
		)
		(fp_line
			(start -0.12065 0.3048)
			(end -0.67945 0.3048)
			(stroke
				(width 0.1)
				(type default)
			)
			(layer "F.Fab")
		)
		(fp_line
			(start 0.120396 0.3048)
			(end 0.120396 0.2794)
			(stroke
				(width 0.1)
				(type default)
			)
			(layer "F.Fab")
		)
		(fp_line
			(start 0.67945 0.3048)
			(end 0.120396 0.3048)
			(stroke
				(width 0.1)
				(type default)
			)
			(layer "F.Fab")
		)
		(fp_line
			(start -0.12065 0.2794)
			(end -0.12065 0.3048)
			(stroke
				(width 0.1)
				(type default)
			)
			(layer "F.Fab")
		)
		(fp_line
			(start 0.120396 0.2794)
			(end -0.12065 0.2794)
			(stroke
				(width 0.1)
				(type default)
			)
			(layer "F.Fab")
		)
		(fp_line
			(start -0.12065 -0.2794)
			(end 0.12065 -0.2794)
			(stroke
				(width 0.1)
				(type default)
			)
			(layer "F.Fab")
		)
		(fp_line
			(start 0.12065 -0.2794)
			(end 0.12065 -0.3048)
			(stroke
				(width 0.1)
				(type default)
			)
			(layer "F.Fab")
		)
		(fp_line
			(start 0.12065 -0.3048)
			(end 0.67945 -0.3048)
			(stroke
				(width 0.1)
				(type default)
			)
			(layer "F.Fab")
		)
		(fp_line
			(start 0.67945 -0.3048)
			(end 0.67945 0.3048)
			(stroke
				(width 0.1)
				(type default)
			)
			(layer "F.Fab")
		)
		(fp_line
			(start -0.67945 -0.305054)
			(end -0.12065 -0.305054)
			(stroke
				(width 0.1)
				(type default)
			)
			(layer "F.Fab")
		)
		(fp_line
			(start -0.12065 -0.305054)
			(end -0.12065 -0.2794)
			(stroke
				(width 0.1)
				(type default)
			)
			(layer "F.Fab")
		)
		(pad "1" smd circle
			(at -0.40005 0 270)
			(size 0 0)
			(layers "F.Cu" "F.Mask" "F.Paste")
			(net "P1V25_SERDES_VDDPLL_PEX2")
		)
		(pad "2" smd circle
			(at 0.40005 0 270)
			(size 0 0)
			(layers "F.Cu" "F.Mask" "F.Paste")
			(net "P1V25_SERDES_VDDPLL_PEX2_C3")
		)
	)
	(footprint ""
		(layer "F.Cu")
		(at 174.164244 -141.6558 180)
		(property "Reference" "R137"
			(at 0 0 180)
			(layer "F.SilkS")
			(hide yes)
			(effects
				(font
					(size 1.27 1.27)
				)
			)
		)
		(property "Value" ""
			(at 0 0 180)
			(layer "F.Fab")
			(effects
				(font
					(size 1.27 1.27)
				)
			)
		)
		(duplicate_pad_numbers_are_jumpers no)
		(fp_line
			(start 0.7874 0.4064)
			(end -0.7874 0.4064)
			(stroke
				(width 0.1524)
				(type default)
			)
			(layer "F.SilkS")
		)
		(fp_line
			(start 0.7874 -0.4064)
			(end 0.7874 0.4064)
			(stroke
				(width 0.1524)
				(type default)
			)
			(layer "F.SilkS")
		)
		(fp_line
			(start -0.7874 0.4064)
			(end -0.7874 -0.4064)
			(stroke
				(width 0.1524)
				(type default)
			)
			(layer "F.SilkS")
		)
		(fp_line
			(start -0.7874 -0.4064)
			(end 0.7874 -0.4064)
			(stroke
				(width 0.1524)
				(type default)
			)
			(layer "F.SilkS")
		)
		(fp_line
			(start 0.67945 0.3048)
			(end 0.120396 0.3048)
			(stroke
				(width 0.1)
				(type default)
			)
			(layer "F.Fab")
		)
		(fp_line
			(start 0.67945 -0.3048)
			(end 0.67945 0.3048)
			(stroke
				(width 0.1)
				(type default)
			)
			(layer "F.Fab")
		)
		(fp_line
			(start 0.12065 -0.2794)
			(end 0.12065 -0.3048)
			(stroke
				(width 0.1)
				(type default)
			)
			(layer "F.Fab")
		)
		(fp_line
			(start 0.12065 -0.3048)
			(end 0.67945 -0.3048)
			(stroke
				(width 0.1)
				(type default)
			)
			(layer "F.Fab")
		)
		(fp_line
			(start 0.120396 0.3048)
			(end 0.120396 0.2794)
			(stroke
				(width 0.1)
				(type default)
			)
			(layer "F.Fab")
		)
		(fp_line
			(start 0.120396 0.2794)
			(end -0.12065 0.2794)
			(stroke
				(width 0.1)
				(type default)
			)
			(layer "F.Fab")
		)
		(fp_line
			(start -0.12065 0.3048)
			(end -0.67945 0.3048)
			(stroke
				(width 0.1)
				(type default)
			)
			(layer "F.Fab")
		)
		(fp_line
			(start -0.12065 0.2794)
			(end -0.12065 0.3048)
			(stroke
				(width 0.1)
				(type default)
			)
			(layer "F.Fab")
		)
		(fp_line
			(start -0.12065 -0.2794)
			(end 0.12065 -0.2794)
			(stroke
				(width 0.1)
				(type default)
			)
			(layer "F.Fab")
		)
		(fp_line
			(start -0.12065 -0.305054)
			(end -0.12065 -0.2794)
			(stroke
				(width 0.1)
				(type default)
			)
			(layer "F.Fab")
		)
		(fp_line
			(start -0.67945 0.3048)
			(end -0.67945 -0.305054)
			(stroke
				(width 0.1)
				(type default)
			)
			(layer "F.Fab")
		)
		(fp_line
			(start -0.67945 -0.305054)
			(end -0.12065 -0.305054)
			(stroke
				(width 0.1)
				(type default)
			)
			(layer "F.Fab")
		)
		(pad "1" smd circle
			(at -0.40005 0 180)
			(size 0 0)
			(layers "F.Cu" "F.Mask" "F.Paste")
			(net "RST_SMB_NIC2_MUX_ISO_N")
		)
		(pad "2" smd circle
			(at 0.40005 0 180)
			(size 0 0)
			(layers "F.Cu" "F.Mask" "F.Paste")
			(net "P3V3_NIC2")
		)
	)
	(footprint ""
		(layer "F.Cu")
		(at 80.019398 -133.480302 180)
		(property "Reference" "C20"
			(at 0 0 180)
			(layer "F.SilkS")
			(hide yes)
			(effects
				(font
					(size 1.27 1.27)
				)
			)
		)
		(property "Value" ""
			(at 0 0 180)
			(layer "F.Fab")
			(effects
				(font
					(size 1.27 1.27)
				)
			)
		)
		(duplicate_pad_numbers_are_jumpers no)
		(fp_line
			(start 0.299974 0.150114)
			(end -0.299974 0.150114)
			(stroke
				(width 0.1)
				(type default)
			)
			(layer "F.Fab")
		)
		(fp_line
			(start 0.299974 -0.150114)
			(end 0.299974 0.150114)
			(stroke
				(width 0.1)
				(type default)
			)
			(layer "F.Fab")
		)
		(fp_line
			(start -0.299974 0.150114)
			(end -0.299974 -0.150114)
			(stroke
				(width 0.1)
				(type default)
			)
			(layer "F.Fab")
		)
		(fp_line
			(start -0.299974 -0.150114)
			(end 0.299974 -0.150114)
			(stroke
				(width 0.1)
				(type default)
			)
			(layer "F.Fab")
		)
		(pad "1" smd rect
			(at -0.2667 0 180)
			(size 0.3048 0.381)
			(layers "F.Cu" "F.Mask" "F.Paste")
			(net "P5E_PEX0_STN0_TX_DN<6>")
		)
		(pad "2" smd rect
			(at 0.2667 0 180)
			(size 0.3048 0.381)
			(layers "F.Cu" "F.Mask" "F.Paste")
			(net "P5E_PEX0_STN0_TX_C_DN<6>")
		)
	)
	(footprint ""
		(layer "F.Cu")
		(at 338.074 -148.971 180)
		(property "Reference" "R4843"
			(at 0 0 180)
			(layer "F.SilkS")
			(hide yes)
			(effects
				(font
					(size 1.27 1.27)
				)
			)
		)
		(property "Value" ""
			(at 0 0 180)
			(layer "F.Fab")
			(effects
				(font
					(size 1.27 1.27)
				)
			)
		)
		(duplicate_pad_numbers_are_jumpers no)
		(fp_line
			(start 0.7874 0.4064)
			(end -0.7874 0.4064)
			(stroke
				(width 0.1524)
				(type default)
			)
			(layer "F.SilkS")
		)
		(fp_line
			(start 0.7874 -0.4064)
			(end 0.7874 0.4064)
			(stroke
				(width 0.1524)
				(type default)
			)
			(layer "F.SilkS")
		)
		(fp_line
			(start -0.7874 0.4064)
			(end -0.7874 -0.4064)
			(stroke
				(width 0.1524)
				(type default)
			)
			(layer "F.SilkS")
		)
		(fp_line
			(start -0.7874 -0.4064)
			(end 0.7874 -0.4064)
			(stroke
				(width 0.1524)
				(type default)
			)
			(layer "F.SilkS")
		)
		(fp_line
			(start 0.67945 0.3048)
			(end 0.120396 0.3048)
			(stroke
				(width 0.1)
				(type default)
			)
			(layer "F.Fab")
		)
		(fp_line
			(start 0.67945 -0.3048)
			(end 0.67945 0.3048)
			(stroke
				(width 0.1)
				(type default)
			)
			(layer "F.Fab")
		)
		(fp_line
			(start 0.12065 -0.2794)
			(end 0.12065 -0.3048)
			(stroke
				(width 0.1)
				(type default)
			)
			(layer "F.Fab")
		)
		(fp_line
			(start 0.12065 -0.3048)
			(end 0.67945 -0.3048)
			(stroke
				(width 0.1)
				(type default)
			)
			(layer "F.Fab")
		)
		(fp_line
			(start 0.120396 0.3048)
			(end 0.120396 0.2794)
			(stroke
				(width 0.1)
				(type default)
			)
			(layer "F.Fab")
		)
		(fp_line
			(start 0.120396 0.2794)
			(end -0.12065 0.2794)
			(stroke
				(width 0.1)
				(type default)
			)
			(layer "F.Fab")
		)
		(fp_line
			(start -0.12065 0.3048)
			(end -0.67945 0.3048)
			(stroke
				(width 0.1)
				(type default)
			)
			(layer "F.Fab")
		)
		(fp_line
			(start -0.12065 0.2794)
			(end -0.12065 0.3048)
			(stroke
				(width 0.1)
				(type default)
			)
			(layer "F.Fab")
		)
		(fp_line
			(start -0.12065 -0.2794)
			(end 0.12065 -0.2794)
			(stroke
				(width 0.1)
				(type default)
			)
			(layer "F.Fab")
		)
		(fp_line
			(start -0.12065 -0.305054)
			(end -0.12065 -0.2794)
			(stroke
				(width 0.1)
				(type default)
			)
			(layer "F.Fab")
		)
		(fp_line
			(start -0.67945 0.3048)
			(end -0.67945 -0.305054)
			(stroke
				(width 0.1)
				(type default)
			)
			(layer "F.Fab")
		)
		(fp_line
			(start -0.67945 -0.305054)
			(end -0.12065 -0.305054)
			(stroke
				(width 0.1)
				(type default)
			)
			(layer "F.Fab")
		)
		(pad "1" smd circle
			(at -0.40005 0 180)
			(size 0 0)
			(layers "F.Cu" "F.Mask" "F.Paste")
			(net "GND")
		)
		(pad "2" smd circle
			(at 0.40005 0 180)
			(size 0 0)
			(layers "F.Cu" "F.Mask" "F.Paste")
			(net "PCA9555_1_PEX3_A2")
		)
	)
	(footprint ""
		(layer "F.Cu")
		(at 233.316018 -78.99019)
		(property "Reference" "R1003"
			(at 0 0 0)
			(layer "F.SilkS")
			(hide yes)
			(effects
				(font
					(size 1.27 1.27)
				)
			)
		)
		(property "Value" ""
			(at 0 0 0)
			(layer "F.Fab")
			(effects
				(font
					(size 1.27 1.27)
				)
			)
		)
		(duplicate_pad_numbers_are_jumpers no)
		(fp_line
			(start -0.7874 -0.4064)
			(end 0.7874 -0.4064)
			(stroke
				(width 0.1524)
				(type default)
			)
			(layer "F.SilkS")
		)
		(fp_line
			(start -0.7874 0.4064)
			(end -0.7874 -0.4064)
			(stroke
				(width 0.1524)
				(type default)
			)
			(layer "F.SilkS")
		)
		(fp_line
			(start 0.7874 -0.4064)
			(end 0.7874 0.4064)
			(stroke
				(width 0.1524)
				(type default)
			)
			(layer "F.SilkS")
		)
		(fp_line
			(start 0.7874 0.4064)
			(end -0.7874 0.4064)
			(stroke
				(width 0.1524)
				(type default)
			)
			(layer "F.SilkS")
		)
		(fp_line
			(start -0.67945 -0.305054)
			(end -0.12065 -0.305054)
			(stroke
				(width 0.1)
				(type default)
			)
			(layer "F.Fab")
		)
		(fp_line
			(start -0.67945 0.3048)
			(end -0.67945 -0.305054)
			(stroke
				(width 0.1)
				(type default)
			)
			(layer "F.Fab")
		)
		(fp_line
			(start -0.12065 -0.305054)
			(end -0.12065 -0.2794)
			(stroke
				(width 0.1)
				(type default)
			)
			(layer "F.Fab")
		)
		(fp_line
			(start -0.12065 -0.2794)
			(end 0.12065 -0.2794)
			(stroke
				(width 0.1)
				(type default)
			)
			(layer "F.Fab")
		)
		(fp_line
			(start -0.12065 0.2794)
			(end -0.12065 0.3048)
			(stroke
				(width 0.1)
				(type default)
			)
			(layer "F.Fab")
		)
		(fp_line
			(start -0.12065 0.3048)
			(end -0.67945 0.3048)
			(stroke
				(width 0.1)
				(type default)
			)
			(layer "F.Fab")
		)
		(fp_line
			(start 0.120396 0.2794)
			(end -0.12065 0.2794)
			(stroke
				(width 0.1)
				(type default)
			)
			(layer "F.Fab")
		)
		(fp_line
			(start 0.120396 0.3048)
			(end 0.120396 0.2794)
			(stroke
				(width 0.1)
				(type default)
			)
			(layer "F.Fab")
		)
		(fp_line
			(start 0.12065 -0.3048)
			(end 0.67945 -0.3048)
			(stroke
				(width 0.1)
				(type default)
			)
			(layer "F.Fab")
		)
		(fp_line
			(start 0.12065 -0.2794)
			(end 0.12065 -0.3048)
			(stroke
				(width 0.1)
				(type default)
			)
			(layer "F.Fab")
		)
		(fp_line
			(start 0.67945 -0.3048)
			(end 0.67945 0.3048)
			(stroke
				(width 0.1)
				(type default)
			)
			(layer "F.Fab")
		)
		(fp_line
			(start 0.67945 0.3048)
			(end 0.120396 0.3048)
			(stroke
				(width 0.1)
				(type default)
			)
			(layer "F.Fab")
		)
		(pad "1" smd circle
			(at -0.40005 0)
			(size 0 0)
			(layers "F.Cu" "F.Mask" "F.Paste")
			(net "PEX_USB2_SEL")
		)
		(pad "2" smd circle
			(at 0.40005 0)
			(size 0 0)
			(layers "F.Cu" "F.Mask" "F.Paste")
			(net "GND")
		)
	)
	(footprint ""
		(layer "F.Cu")
		(at 220.812868 -104.912668 90)
		(property "Reference" "C903"
			(at 0 0 90)
			(layer "F.SilkS")
			(hide yes)
			(effects
				(font
					(size 1.27 1.27)
				)
			)
		)
		(property "Value" ""
			(at 0 0 90)
			(layer "F.Fab")
			(effects
				(font
					(size 1.27 1.27)
				)
			)
		)
		(duplicate_pad_numbers_are_jumpers no)
		(fp_line
			(start 0.7874 -0.4064)
			(end 0.7874 0.4064)
			(stroke
				(width 0.1524)
				(type default)
			)
			(layer "F.SilkS")
		)
		(fp_line
			(start -0.7874 -0.4064)
			(end 0.7874 -0.4064)
			(stroke
				(width 0.1524)
				(type default)
			)
			(layer "F.SilkS")
		)
		(fp_line
			(start 0.7874 0.4064)
			(end -0.7874 0.4064)
			(stroke
				(width 0.1524)
				(type default)
			)
			(layer "F.SilkS")
		)
		(fp_line
			(start -0.7874 0.4064)
			(end -0.7874 -0.4064)
			(stroke
				(width 0.1524)
				(type default)
			)
			(layer "F.SilkS")
		)
		(fp_line
			(start -0.12065 -0.305054)
			(end -0.12065 -0.2794)
			(stroke
				(width 0.1)
				(type default)
			)
			(layer "F.Fab")
		)
		(fp_line
			(start -0.67945 -0.305054)
			(end -0.12065 -0.305054)
			(stroke
				(width 0.1)
				(type default)
			)
			(layer "F.Fab")
		)
		(fp_line
			(start 0.67945 -0.3048)
			(end 0.67945 0.3048)
			(stroke
				(width 0.1)
				(type default)
			)
			(layer "F.Fab")
		)
		(fp_line
			(start 0.12065 -0.3048)
			(end 0.67945 -0.3048)
			(stroke
				(width 0.1)
				(type default)
			)
			(layer "F.Fab")
		)
		(fp_line
			(start 0.12065 -0.2794)
			(end 0.12065 -0.3048)
			(stroke
				(width 0.1)
				(type default)
			)
			(layer "F.Fab")
		)
		(fp_line
			(start -0.12065 -0.2794)
			(end 0.12065 -0.2794)
			(stroke
				(width 0.1)
				(type default)
			)
			(layer "F.Fab")
		)
		(fp_line
			(start 0.120396 0.2794)
			(end -0.12065 0.2794)
			(stroke
				(width 0.1)
				(type default)
			)
			(layer "F.Fab")
		)
		(fp_line
			(start -0.12065 0.2794)
			(end -0.12065 0.3048)
			(stroke
				(width 0.1)
				(type default)
			)
			(layer "F.Fab")
		)
		(fp_line
			(start 0.67945 0.3048)
			(end 0.120396 0.3048)
			(stroke
				(width 0.1)
				(type default)
			)
			(layer "F.Fab")
		)
		(fp_line
			(start 0.120396 0.3048)
			(end 0.120396 0.2794)
			(stroke
				(width 0.1)
				(type default)
			)
			(layer "F.Fab")
		)
		(fp_line
			(start -0.12065 0.3048)
			(end -0.67945 0.3048)
			(stroke
				(width 0.1)
				(type default)
			)
			(layer "F.Fab")
		)
		(fp_line
			(start -0.67945 0.3048)
			(end -0.67945 -0.305054)
			(stroke
				(width 0.1)
				(type default)
			)
			(layer "F.Fab")
		)
		(pad "1" smd circle
			(at -0.40005 0 90)
			(size 0 0)
			(layers "F.Cu" "F.Mask" "F.Paste")
			(net "P3V3_AUX")
		)
		(pad "2" smd circle
			(at 0.40005 0 90)
			(size 0 0)
			(layers "F.Cu" "F.Mask" "F.Paste")
			(net "GND")
		)
	)
	(footprint ""
		(layer "F.Cu")
		(at 365.506 -196.723 180)
		(property "Reference" "R4690"
			(at 0 0 180)
			(layer "F.SilkS")
			(hide yes)
			(effects
				(font
					(size 1.27 1.27)
				)
			)
		)
		(property "Value" ""
			(at 0 0 180)
			(layer "F.Fab")
			(effects
				(font
					(size 1.27 1.27)
				)
			)
		)
		(duplicate_pad_numbers_are_jumpers no)
		(fp_line
			(start 0.7874 0.4064)
			(end -0.7874 0.4064)
			(stroke
				(width 0.1524)
				(type default)
			)
			(layer "F.SilkS")
		)
		(fp_line
			(start 0.7874 -0.4064)
			(end 0.7874 0.4064)
			(stroke
				(width 0.1524)
				(type default)
			)
			(layer "F.SilkS")
		)
		(fp_line
			(start -0.7874 0.4064)
			(end -0.7874 -0.4064)
			(stroke
				(width 0.1524)
				(type default)
			)
			(layer "F.SilkS")
		)
		(fp_line
			(start -0.7874 -0.4064)
			(end 0.7874 -0.4064)
			(stroke
				(width 0.1524)
				(type default)
			)
			(layer "F.SilkS")
		)
		(fp_line
			(start 0.67945 0.3048)
			(end 0.120396 0.3048)
			(stroke
				(width 0.1)
				(type default)
			)
			(layer "F.Fab")
		)
		(fp_line
			(start 0.67945 -0.3048)
			(end 0.67945 0.3048)
			(stroke
				(width 0.1)
				(type default)
			)
			(layer "F.Fab")
		)
		(fp_line
			(start 0.12065 -0.2794)
			(end 0.12065 -0.3048)
			(stroke
				(width 0.1)
				(type default)
			)
			(layer "F.Fab")
		)
		(fp_line
			(start 0.12065 -0.3048)
			(end 0.67945 -0.3048)
			(stroke
				(width 0.1)
				(type default)
			)
			(layer "F.Fab")
		)
		(fp_line
			(start 0.120396 0.3048)
			(end 0.120396 0.2794)
			(stroke
				(width 0.1)
				(type default)
			)
			(layer "F.Fab")
		)
		(fp_line
			(start 0.120396 0.2794)
			(end -0.12065 0.2794)
			(stroke
				(width 0.1)
				(type default)
			)
			(layer "F.Fab")
		)
		(fp_line
			(start -0.12065 0.3048)
			(end -0.67945 0.3048)
			(stroke
				(width 0.1)
				(type default)
			)
			(layer "F.Fab")
		)
		(fp_line
			(start -0.12065 0.2794)
			(end -0.12065 0.3048)
			(stroke
				(width 0.1)
				(type default)
			)
			(layer "F.Fab")
		)
		(fp_line
			(start -0.12065 -0.2794)
			(end 0.12065 -0.2794)
			(stroke
				(width 0.1)
				(type default)
			)
			(layer "F.Fab")
		)
		(fp_line
			(start -0.12065 -0.305054)
			(end -0.12065 -0.2794)
			(stroke
				(width 0.1)
				(type default)
			)
			(layer "F.Fab")
		)
		(fp_line
			(start -0.67945 0.3048)
			(end -0.67945 -0.305054)
			(stroke
				(width 0.1)
				(type default)
			)
			(layer "F.Fab")
		)
		(fp_line
			(start -0.67945 -0.305054)
			(end -0.12065 -0.305054)
			(stroke
				(width 0.1)
				(type default)
			)
			(layer "F.Fab")
		)
		(pad "1" smd circle
			(at -0.40005 0 180)
			(size 0 0)
			(layers "F.Cu" "F.Mask" "F.Paste")
			(net "PRSNT_SSD5_FPGA_PCA9555_N")
		)
		(pad "2" smd circle
			(at 0.40005 0 180)
			(size 0 0)
			(layers "F.Cu" "F.Mask" "F.Paste")
			(net "PRSNT_SSD5_FPGA_R_N")
		)
	)
)
